# BASEBOARD_FAB2 (Tioga Pass) — schematic netlist excerpt (pin names and nets, part order shuffled) for the footprints in the layout excerpt that follows; sources: Cadence DE-HDL packaged netlist, KiCad conversion of Wiwynn_Tioga_Pass_MB.brd

U8W1  74CBTLV1G125  IC  pkg SMLF  page 245
  OE_N  = JTAG_RISER_N
  A  = JTAG_PLD_TDO
  B  = JTAG_RISER_TDI_R

C25W71  CAP  1.0UF 16V 10% X6S  pkg 0402  page 149 : A = P3V3_USB2A_ALG ; B = GND
CT69  CAP  1000PF 50V 10% X7R  pkg 0402LF  page 236 : A = A_TSENSE_P1V05_PCH_STBY_TMON ; B = GND

(kicad_pcb
	(version 20260206)
	(generator "pcbnew")
	(generator_version "10.0")
	(general
		(thickness 1.6)
		(legacy_teardrops no)
	)
	(paper "A4")
	(title_block
		(title "Wiwynn_Tioga_Pass_MB.brd")
		(comment 1 "Tioga Pass / footprints 2658-2660 of 4770")
	)
	(layers
		(0 "F.Cu" signal "TOP")
		(4 "In1.Cu" signal "L2GND")
		(6 "In2.Cu" signal "L3")
		(8 "In3.Cu" signal "L4GND")
		(10 "In4.Cu" signal "L5")
		(12 "In5.Cu" signal "L6GND")
		(14 "In6.Cu" signal "L7VCC")
		(16 "In7.Cu" signal "L8VCC")
		(18 "In8.Cu" signal "L9GND")
		(20 "In9.Cu" signal "L10")
		(22 "In10.Cu" signal "L11GND")
		(24 "In11.Cu" signal "L12")
		(26 "In12.Cu" signal "L13GND")
		(2 "B.Cu" signal "BOTTOM")
		(9 "F.Adhes" user "F.Adhesive")
		(11 "B.Adhes" user "B.Adhesive")
		(13 "F.Paste" user "Package Geometry/Pastemask Top")
		(15 "B.Paste" user "Package Geometry/Pastemask Bottom")
		(5 "F.SilkS" user "Ref Des/Silkscreen Top")
		(7 "B.SilkS" user "Ref Des/Silkscreen Bottom")
		(1 "F.Mask" user "Board Geometry/Soldermask Top")
		(3 "B.Mask" user "Board Geometry/Soldermask Bottom")
		(17 "Dwgs.User" user "User.Drawings")
		(19 "Cmts.User" user "User.Comments")
		(21 "Eco1.User" user "User.Eco1")
		(23 "Eco2.User" user "User.Eco2")
		(25 "Edge.Cuts" user "Board Geometry/Outline")
		(27 "Margin" user)
		(31 "F.CrtYd" user "Package Geometry/Place Bound Top")
		(29 "B.CrtYd" user "Package Geometry/Place Bound Bottom")
		(35 "F.Fab" user "Ref Des/Assembly Top")
		(33 "B.Fab" user "Ref Des/Assembly Bottom")
	)
	(footprint ""
		(layer "B.Cu")
		(at 388.9248 -3.103372)
		(property "Reference" "U8W1"
			(at 0.14986 2.621788 0)
			(unlocked yes)
			(layer "B.SilkS")
			(effects
				(font
					(size 1.27 0.964946)
					(thickness 0.000001)
				)
				(justify left mirror)
			)
		)
		(property "Value" ""
			(at 0 0 0)
			(layer "B.Fab")
			(effects
				(font
					(size 1.27 1.27)
				)
				(justify mirror)
			)
		)
		(duplicate_pad_numbers_are_jumpers no)
		(fp_circle
			(center 0.4699 -0.8382)
			(end 0.5969 -0.8382)
			(stroke
				(width 0.254)
				(type default)
			)
			(fill no)
			(layer "B.SilkS")
		)
		(fp_poly
			(pts
				(xy -0.21463 -0.450088) (xy -1.56337 -0.450088) (xy -1.56337 1.75006) (xy -0.21463 1.75006)
			)
			(stroke
				(width 0)
				(type default)
			)
			(fill no)
			(layer "B.CrtYd")
		)
		(fp_line
			(start -1.56337 -0.450088)
			(end -1.56337 1.75006)
			(stroke
				(width 0.1)
				(type default)
			)
			(layer "B.Fab")
		)
		(fp_line
			(start -1.56337 1.75006)
			(end -0.21463 1.75006)
			(stroke
				(width 0.1)
				(type default)
			)
			(layer "B.Fab")
		)
		(fp_line
			(start -0.21463 -0.450088)
			(end -1.56337 -0.450088)
			(stroke
				(width 0.1)
				(type default)
			)
			(layer "B.Fab")
		)
		(fp_line
			(start -0.21463 1.75006)
			(end -0.21463 -0.450088)
			(stroke
				(width 0.1)
				(type default)
			)
			(layer "B.Fab")
		)
		(fp_circle
			(center 0.4699 -0.8382)
			(end 0.5969 -0.8382)
			(stroke
				(width 0.254)
				(type default)
			)
			(fill no)
			(layer "B.Fab")
		)
		(pad "1" smd rect
			(at 0 0 180)
			(size 1.016 0.381)
			(layers "B.Cu" "B.Mask" "B.Paste")
			(net "JTAG_RISER_N")
		)
		(pad "2" smd rect
			(at 0 0.649986 180)
			(size 1.016 0.381)
			(layers "B.Cu" "B.Mask" "B.Paste")
			(net "JTAG_PLD_TDO")
		)
		(pad "3" smd rect
			(at 0 1.299972 180)
			(size 1.016 0.381)
			(layers "B.Cu" "B.Mask" "B.Paste")
			(net "GND")
		)
		(pad "4" smd rect
			(at -1.778 1.299972 180)
			(size 1.016 0.381)
			(layers "B.Cu" "B.Mask" "B.Paste")
			(net "JTAG_RISER_TDI_R")
		)
		(pad "5" smd rect
			(at -1.778 0 180)
			(size 1.016 0.381)
			(layers "B.Cu" "B.Mask" "B.Paste")
			(net "P3V3_STBY")
		)
	)
	(footprint ""
		(layer "B.Cu")
		(at 384.0734 -158.26994 -90)
		(property "Reference" "CT69"
			(at 0.8382 -0.84963 270)
			(unlocked yes)
			(layer "B.SilkS")
			(effects
				(font
					(size 0.7874 0.5842)
					(thickness 0.1524)
				)
				(justify left mirror)
			)
		)
		(property "Value" ""
			(at 0 0 90)
			(layer "B.Fab")
			(effects
				(font
					(size 1.27 1.27)
				)
				(justify mirror)
			)
		)
		(duplicate_pad_numbers_are_jumpers no)
		(fp_poly
			(pts
				(xy -0.3048 -0.1016) (xy -0.3048 0.9906) (xy 0.3048 0.9906) (xy 0.3048 -0.1016)
			)
			(stroke
				(width 0)
				(type default)
			)
			(fill no)
			(layer "B.CrtYd")
		)
		(fp_line
			(start -0.3048 0.9906)
			(end -0.3048 -0.1016)
			(stroke
				(width 0.1)
				(type default)
			)
			(layer "B.Fab")
		)
		(fp_line
			(start 0.3048 0.9906)
			(end -0.3048 0.9906)
			(stroke
				(width 0.1)
				(type default)
			)
			(layer "B.Fab")
		)
		(fp_line
			(start -0.3048 -0.1016)
			(end 0.3048 -0.1016)
			(stroke
				(width 0.1)
				(type default)
			)
			(layer "B.Fab")
		)
		(fp_line
			(start 0.3048 -0.1016)
			(end 0.3048 0.9906)
			(stroke
				(width 0.1)
				(type default)
			)
			(layer "B.Fab")
		)
		(pad "1" smd rect
			(at 0 0 90)
			(size 0.508 0.508)
			(layers "B.Cu" "B.Mask" "B.Paste")
			(net "A_TSENSE_P1V05_PCH_STBY_TMON")
		)
		(pad "2" smd rect
			(at 0 0.889 90)
			(size 0.508 0.508)
			(layers "B.Cu" "B.Mask" "B.Paste")
			(net "GND")
		)
		(zone
			(layer "B.Cu")
			(hatch none 0.5)
			(connect_pads
				(clearance 0)
			)
			(min_thickness 0.25)
			(keepout
				(tracks not_allowed)
				(vias allowed)
				(pads allowed)
				(copperpour not_allowed)
				(footprints allowed)
			)
			(placement
				(enabled no)
				(sheetname "")
			)
			(fill
				(thermal_gap 0.5)
				(thermal_bridge_width 0.5)
				(island_removal_mode 0)
			)
			(polygon
				(pts
					(xy 383.4384 -158.01594) (xy 383.4384 -158.52394) (xy 383.8194 -158.52394) (xy 383.8194 -158.01594)
				)
			)
		)
		(zone
			(layer "B.Cu")
			(hatch none 0.5)
			(connect_pads
				(clearance 0)
			)
			(min_thickness 0.25)
			(keepout
				(tracks allowed)
				(vias not_allowed)
				(pads allowed)
				(copperpour not_allowed)
				(footprints allowed)
			)
			(placement
				(enabled no)
				(sheetname "")
			)
			(fill
				(thermal_gap 0.5)
				(thermal_bridge_width 0.5)
				(island_removal_mode 0)
			)
			(polygon
				(pts
					(xy 383.8194 -158.01594) (xy 383.8194 -158.52394) (xy 383.4384 -158.52394) (xy 383.4384 -158.01594)
				)
			)
		)
	)
	(footprint ""
		(layer "B.Cu")
		(at 400.409156 -30.806898)
		(property "Reference" "C25W71"
			(at 0.8382 -0.67818 0)
			(unlocked yes)
			(layer "B.SilkS")
			(effects
				(font
					(size 0.4064 0.254)
					(thickness 0.1524)
				)
				(justify left mirror)
			)
		)
		(property "Value" ""
			(at 0 0 0)
			(layer "B.Fab")
			(effects
				(font
					(size 1.27 1.27)
				)
				(justify mirror)
			)
		)
		(duplicate_pad_numbers_are_jumpers no)
		(fp_poly
			(pts
				(xy -0.3048 -0.1016) (xy -0.3048 0.9906) (xy 0.3048 0.9906) (xy 0.3048 -0.1016)
			)
			(stroke
				(width 0)
				(type default)
			)
			(fill no)
			(layer "B.CrtYd")
		)
		(fp_line
			(start -0.3048 -0.1016)
			(end 0.3048 -0.1016)
			(stroke
				(width 0.1)
				(type default)
			)
			(layer "B.Fab")
		)
		(fp_line
			(start -0.3048 0.9906)
			(end -0.3048 -0.1016)
			(stroke
				(width 0.1)
				(type default)
			)
			(layer "B.Fab")
		)
		(fp_line
			(start 0.3048 -0.1016)
			(end 0.3048 0.9906)
			(stroke
				(width 0.1)
				(type default)
			)
			(layer "B.Fab")
		)
		(fp_line
			(start 0.3048 0.9906)
			(end -0.3048 0.9906)
			(stroke
				(width 0.1)
				(type default)
			)
			(layer "B.Fab")
		)
		(pad "1" smd rect
			(at 0 0 180)
			(size 0.508 0.508)
			(layers "B.Cu" "B.Mask" "B.Paste")
			(net "P3V3_USB2A_ALG")
		)
		(pad "2" smd rect
			(at 0 0.889 180)
			(size 0.508 0.508)
			(layers "B.Cu" "B.Mask" "B.Paste")
			(net "GND")
		)
		(zone
			(layer "B.Cu")
			(hatch none 0.5)
			(connect_pads
				(clearance 0)
			)
			(min_thickness 0.25)
			(keepout
				(tracks allowed)
				(vias not_allowed)
				(pads allowed)
				(copperpour not_allowed)
				(footprints allowed)
			)
			(placement
				(enabled no)
				(sheetname "")
			)
			(fill
				(thermal_gap 0.5)
				(thermal_bridge_width 0.5)
				(island_removal_mode 0)
			)
			(polygon
				(pts
					(xy 400.663156 -30.552898) (xy 400.155156 -30.552898) (xy 400.155156 -30.171898) (xy 400.663156 -30.171898)
				)
			)
		)
		(zone
			(layer "B.Cu")
			(hatch none 0.5)
			(connect_pads
				(clearance 0)
			)
			(min_thickness 0.25)
			(keepout
				(tracks not_allowed)
				(vias allowed)
				(pads allowed)
				(copperpour not_allowed)
				(footprints allowed)
			)
			(placement
				(enabled no)
				(sheetname "")
			)
			(fill
				(thermal_gap 0.5)
				(thermal_bridge_width 0.5)
				(island_removal_mode 0)
			)
			(polygon
				(pts
					(xy 400.663156 -30.171898) (xy 400.155156 -30.171898) (xy 400.155156 -30.552898) (xy 400.663156 -30.552898)
				)
			)
		)
	)
)
